(kicad_pcb
	(version 20260206)
	(generator "pcbnew")
	(generator_version "10.0")
	(general
		(thickness 1.6)
		(legacy_teardrops no)
	)
	(paper "A4")
	(title_block
		(title "baseboard — 13948-1b.1110WZS1818.brd")
		(comment 1 "Honey Badger (Wiwynn) / footprints 1817-1821 of 2523")
	)
	(layers
		(0 "F.Cu" signal "TOP")
		(4 "In1.Cu" signal "L2GND")
		(6 "In2.Cu" signal "L3")
		(8 "In3.Cu" signal "L4VCC")
		(10 "In4.Cu" signal "L5VCC")
		(12 "In5.Cu" signal "L6")
		(14 "In6.Cu" signal "L7GND")
		(2 "B.Cu" signal "BOTTOM")
		(9 "F.Adhes" user "F.Adhesive")
		(11 "B.Adhes" user "B.Adhesive")
		(13 "F.Paste" user "Package Geometry/Pastemask Top")
		(15 "B.Paste" user "Package Geometry/Pastemask Bottom")
		(5 "F.SilkS" user "Ref Des/Silkscreen Top")
		(7 "B.SilkS" user "Ref Des/Silkscreen Bottom")
		(1 "F.Mask" user "Board Geometry/Soldermask Top")
		(3 "B.Mask" user "Board Geometry/Soldermask Bottom")
		(17 "Dwgs.User" user "User.Drawings")
		(19 "Cmts.User" user "User.Comments")
		(21 "Eco1.User" user "User.Eco1")
		(23 "Eco2.User" user "User.Eco2")
		(25 "Edge.Cuts" user "Board Geometry/Outline")
		(27 "Margin" user)
		(31 "F.CrtYd" user "Package Geometry/Place Bound Top")
		(29 "B.CrtYd" user "Package Geometry/Place Bound Bottom")
		(35 "F.Fab" user "Ref Des/Assembly Top")
		(33 "B.Fab" user "Ref Des/Assembly Bottom")
	)
	(footprint ""
		(layer "B.Cu")
		(at 172.3136 -101.7524 180)
		(property "Reference" "PC186"
			(at 0 0 0)
			(layer "B.SilkS")
			(hide yes)
			(effects
				(font
					(size 1.27 1.27)
				)
				(justify mirror)
			)
		)
		(property "Value" "SCD1U16V2KX-3GP"
			(at -1.1811 -2.7051 180)
			(unlocked yes)
			(layer "B.Fab")
			(hide yes)
			(effects
				(font
					(size 1.016 1.016)
					(thickness 0.1524)
				)
				(justify mirror)
			)
		)
		(property "Device Type" "C402H22"
			(at -1.1811 -4.2291 180)
			(unlocked yes)
			(layer "B.Fab")
			(hide yes)
			(effects
				(font
					(size 1.016 1.016)
					(thickness 0.1524)
				)
				(justify mirror)
			)
		)
		(duplicate_pad_numbers_are_jumpers no)
		(fp_rect
			(start 0.4318 0.9525)
			(end -0.4318 -0.9525)
			(stroke
				(width 0)
				(type default)
			)
			(fill no)
			(layer "B.CrtYd")
		)
		(fp_rect
			(start 0.4318 0.9525)
			(end -0.4318 -0.9525)
			(stroke
				(width 0)
				(type default)
			)
			(fill no)
			(layer "B.Fab")
		)
		(pad "1" smd custom
			(at 0 -0.4445)
			(size 0.1524 0.1524)
			(layers "B.Cu" "B.Mask" "B.Paste")
			(net "P0V9_E")
			(options
				(clearance outline)
				(anchor circle)
			)
			(primitives
				(gr_poly
					(pts
						(arc
							(start 0.3048 0.2032)
							(mid 0.275042 0.275042)
							(end 0.2032 0.3048)
						)
						(arc
							(start -0.2032 0.3048)
							(mid -0.275042 0.275042)
							(end -0.3048 0.2032)
						)
						(arc
							(start -0.3048 -0.2032)
							(mid -0.275042 -0.275042)
							(end -0.2032 -0.3048)
						)
						(arc
							(start 0.2032 -0.3048)
							(mid 0.275042 -0.275042)
							(end 0.3048 -0.2032)
						)
					)
					(width 0)
					(fill yes)
				)
			)
		)
		(pad "2" smd custom
			(at 0 0.4445)
			(size 0.1524 0.1524)
			(layers "B.Cu" "B.Mask" "B.Paste")
			(net "P0V9_E_SW_R")
			(options
				(clearance outline)
				(anchor circle)
			)
			(primitives
				(gr_poly
					(pts
						(arc
							(start 0.3048 0.2032)
							(mid 0.275042 0.275042)
							(end 0.2032 0.3048)
						)
						(arc
							(start -0.2032 0.3048)
							(mid -0.275042 0.275042)
							(end -0.3048 0.2032)
						)
						(arc
							(start -0.3048 -0.2032)
							(mid -0.275042 -0.275042)
							(end -0.2032 -0.3048)
						)
						(arc
							(start 0.2032 -0.3048)
							(mid 0.275042 -0.275042)
							(end 0.3048 -0.2032)
						)
					)
					(width 0)
					(fill yes)
				)
			)
		)
	)
	(footprint ""
		(layer "B.Cu")
		(at 98.000566 -46.1518 -90)
		(property "Reference" "SC1021"
			(at 0 0 90)
			(layer "B.SilkS")
			(hide yes)
			(effects
				(font
					(size 1.27 1.27)
				)
				(justify mirror)
			)
		)
		(property "Value" "SC10U6D3V5KX-4GP"
			(at 0.0762 -6.1214 270)
			(unlocked yes)
			(layer "B.Fab")
			(hide yes)
			(effects
				(font
					(size 1.016 1.016)
					(thickness 0.1524)
				)
				(justify mirror)
			)
		)
		(property "Device Type" "C805H58"
			(at 0.0762 -8.1534 270)
			(unlocked yes)
			(layer "B.Fab")
			(hide yes)
			(effects
				(font
					(size 1.016 1.016)
					(thickness 0.1524)
				)
				(justify mirror)
			)
		)
		(duplicate_pad_numbers_are_jumpers no)
		(fp_line
			(start -0.635 0)
			(end 0.635 0)
			(stroke
				(width 0.508)
				(type default)
			)
			(layer "B.SilkS")
		)
		(fp_rect
			(start 0.9652 1.778)
			(end -0.9652 -1.778)
			(stroke
				(width 0)
				(type default)
			)
			(fill no)
			(layer "B.CrtYd")
		)
		(fp_poly
			(pts
				(xy 0.9652 -1.778) (xy -0.9652 -1.778) (xy -0.9652 1.778) (xy 0.9652 1.778)
			)
			(stroke
				(width 0)
				(type default)
			)
			(fill no)
			(layer "B.Fab")
		)
		(pad "1" smd rect
			(at 0 -0.9652 90)
			(size 1.397 1.143)
			(layers "B.Cu" "B.Mask" "B.Paste")
			(net "P0V955_C")
		)
		(pad "2" smd rect
			(at 0 0.9652 90)
			(size 1.397 1.143)
			(layers "B.Cu" "B.Mask" "B.Paste")
			(net "GND")
		)
	)
	(footprint ""
		(layer "B.Cu")
		(at 115.640612 -214.884 180)
		(property "Reference" "SU77"
			(at 0 0 0)
			(layer "B.SilkS")
			(hide yes)
			(effects
				(font
					(size 1.27 1.27)
				)
				(justify mirror)
			)
		)
		(property "Value" "PI2EQX6812ZHE-GP"
			(at -6.6548 -1.7526 180)
			(unlocked yes)
			(layer "B.Fab")
			(hide yes)
			(effects
				(font
					(size 1.016 1.016)
					(thickness 0.1524)
				)
				(justify mirror)
			)
		)
		(property "Device Type" "QFN42-G7722H34"
			(at -6.6548 -3.2766 180)
			(unlocked yes)
			(layer "B.Fab")
			(hide yes)
			(effects
				(font
					(size 1.016 1.016)
					(thickness 0.1524)
				)
				(justify mirror)
			)
		)
		(duplicate_pad_numbers_are_jumpers no)
		(fp_line
			(start 5.5118 2.7686)
			(end 4.2418 2.7686)
			(stroke
				(width 0.1524)
				(type default)
			)
			(layer "B.SilkS")
		)
		(fp_line
			(start 5.5118 1.4986)
			(end 5.5118 2.7686)
			(stroke
				(width 0.1524)
				(type default)
			)
			(layer "B.SilkS")
		)
		(fp_line
			(start 5.5118 -2.7686)
			(end 5.5118 -1.4986)
			(stroke
				(width 0.1524)
				(type default)
			)
			(layer "B.SilkS")
		)
		(fp_line
			(start 5.2832 0.2413)
			(end 6.0452 0.2413)
			(stroke
				(width 0.1524)
				(type default)
			)
			(layer "B.SilkS")
		)
		(fp_line
			(start 4.2418 -2.7686)
			(end 5.5118 -2.7686)
			(stroke
				(width 0.1524)
				(type default)
			)
			(layer "B.SilkS")
		)
		(fp_line
			(start 3.0099 -3.048)
			(end 3.0099 -2.54)
			(stroke
				(width 0.1524)
				(type default)
			)
			(layer "B.SilkS")
		)
		(fp_line
			(start 2.4892 2.54)
			(end 2.4892 3.048)
			(stroke
				(width 0.1524)
				(type default)
			)
			(layer "B.SilkS")
		)
		(fp_line
			(start 0.508 -3.302)
			(end 0.508 -2.54)
			(stroke
				(width 0.1524)
				(type default)
			)
			(layer "B.SilkS")
		)
		(fp_line
			(start -0.0127 2.54)
			(end -0.0127 3.302)
			(stroke
				(width 0.1524)
				(type default)
			)
			(layer "B.SilkS")
		)
		(fp_line
			(start -1.9939 -3.048)
			(end -1.9939 -2.54)
			(stroke
				(width 0.1524)
				(type default)
			)
			(layer "B.SilkS")
		)
		(fp_line
			(start -2.5019 2.54)
			(end -2.5019 3.048)
			(stroke
				(width 0.1524)
				(type default)
			)
			(layer "B.SilkS")
		)
		(fp_line
			(start -4.2418 2.7686)
			(end -5.5118 2.7686)
			(stroke
				(width 0.1524)
				(type default)
			)
			(layer "B.SilkS")
		)
		(fp_line
			(start -5.2832 0.254)
			(end -6.0452 0.254)
			(stroke
				(width 0.1524)
				(type default)
			)
			(layer "B.SilkS")
		)
		(fp_line
			(start -5.5118 2.7686)
			(end -5.5118 1.4986)
			(stroke
				(width 0.1524)
				(type default)
			)
			(layer "B.SilkS")
		)
		(fp_poly
			(pts
				(xy -4.2418 -2.7686) (xy -5.5118 -2.7686) (xy -5.5118 -1.4986)
			)
			(stroke
				(width 0)
				(type default)
			)
			(fill yes)
			(layer "B.SilkS")
		)
		(fp_rect
			(start 4.4958 1.7526)
			(end -4.4958 -1.7526)
			(stroke
				(width 0)
				(type default)
			)
			(fill no)
			(layer "B.CrtYd")
		)
		(fp_poly
			(pts
				(xy 5.5118 2.7686) (xy 5.5118 -2.7686) (xy 4.4958 -2.7686) (xy 4.4958 1.7526) (xy -4.4958 1.7526)
				(xy -4.4958 -1.7526) (xy 4.49072 -1.7526) (xy 4.49072 -2.7686) (xy -5.5118 -2.7686) (xy -5.5118 2.7686)
			)
			(stroke
				(width 0)
				(type default)
			)
			(fill no)
			(layer "B.CrtYd")
		)
		(fp_rect
			(start 5.5118 2.7686)
			(end -5.5118 -2.7686)
			(stroke
				(width 0)
				(type default)
			)
			(fill no)
			(layer "B.Fab")
		)
		(pad "1" smd rect
			(at -3.999992 -1.778)
			(size 0.3048 0.9652)
			(layers "B.Cu" "B.Mask" "B.Paste")
			(net "REDV_I2C_SEL1A")
		)
		(pad "2" smd rect
			(at -3.50012 -1.778)
			(size 0.3048 0.9652)
			(layers "B.Cu" "B.Mask" "B.Paste")
			(net "Net_1005")
		)
		(pad "3" smd rect
			(at -2.999994 -1.778)
			(size 0.3048 0.9652)
			(layers "B.Cu" "B.Mask" "B.Paste")
			(net "1.2V_REDV")
		)
		(pad "4" smd rect
			(at -2.500122 -1.778)
			(size 0.3048 0.9652)
			(layers "B.Cu" "B.Mask" "B.Paste")
			(net "SAS_HDD_REDV_SER_TX7_P")
		)
		(pad "5" smd rect
			(at -1.999996 -1.778)
			(size 0.3048 0.9652)
			(layers "B.Cu" "B.Mask" "B.Paste")
			(net "SAS_HDD_REDV_SER_TX7_N")
		)
		(pad "6" smd rect
			(at -1.500124 -1.778)
			(size 0.3048 0.9652)
			(layers "B.Cu" "B.Mask" "B.Paste")
			(net "SAS_HDD_REDV_SER_RX7_P")
		)
		(pad "7" smd rect
			(at -0.999998 -1.778)
			(size 0.3048 0.9652)
			(layers "B.Cu" "B.Mask" "B.Paste")
			(net "SAS_HDD_REDV_SER_RX7_N")
		)
		(pad "8" smd rect
			(at -0.500126 -1.778)
			(size 0.3048 0.9652)
			(layers "B.Cu" "B.Mask" "B.Paste")
			(net "1.2V_REDV")
		)
		(pad "9" smd rect
			(at 0 -1.778)
			(size 0.3048 0.9652)
			(layers "B.Cu" "B.Mask" "B.Paste")
			(net "1.2V_REDV")
		)
		(pad "10" smd rect
			(at 0.500126 -1.778)
			(size 0.3048 0.9652)
			(layers "B.Cu" "B.Mask" "B.Paste")
			(net "SAS_HDD_REDV_SER_TX8_P")
		)
		(pad "11" smd rect
			(at 0.999998 -1.778)
			(size 0.3048 0.9652)
			(layers "B.Cu" "B.Mask" "B.Paste")
			(net "SAS_HDD_REDV_SER_TX8_N")
		)
		(pad "12" smd rect
			(at 1.500124 -1.778)
			(size 0.3048 0.9652)
			(layers "B.Cu" "B.Mask" "B.Paste")
			(net "SAS_HDD_REDV_SER_RX8_P")
		)
		(pad "13" smd rect
			(at 1.999996 -1.778)
			(size 0.3048 0.9652)
			(layers "B.Cu" "B.Mask" "B.Paste")
			(net "SAS_HDD_REDV_SER_RX8_N")
		)
		(pad "14" smd rect
			(at 2.500122 -1.778)
			(size 0.3048 0.9652)
			(layers "B.Cu" "B.Mask" "B.Paste")
			(net "1.2V_REDV")
		)
		(pad "15" smd rect
			(at 2.999994 -1.778)
			(size 0.3048 0.9652)
			(layers "B.Cu" "B.Mask" "B.Paste")
			(net "REDV_MODE")
		)
		(pad "16" smd rect
			(at 3.50012 -1.778)
			(size 0.3048 0.9652)
			(layers "B.Cu" "B.Mask" "B.Paste")
			(net "REDV_D2_B")
		)
		(pad "17" smd rect
			(at 3.999992 -1.778)
			(size 0.3048 0.9652)
			(layers "B.Cu" "B.Mask" "B.Paste")
			(net "REDV_I2C_A4")
		)
		(pad "18" smd rect
			(at 4.5212 -0.750062)
			(size 0.9652 0.3048)
			(layers "B.Cu" "B.Mask" "B.Paste")
			(net "Net_1007")
		)
		(pad "19" smd rect
			(at 4.5212 -0.249936)
			(size 0.9652 0.3048)
			(layers "B.Cu" "B.Mask" "B.Paste")
			(net "REDV_D1_B")
		)
		(pad "20" smd rect
			(at 4.5212 0.249936)
			(size 0.9652 0.3048)
			(layers "B.Cu" "B.Mask" "B.Paste")
			(net "Net_1006")
		)
		(pad "21" smd rect
			(at 4.5212 0.750062)
			(size 0.9652 0.3048)
			(layers "B.Cu" "B.Mask" "B.Paste")
			(net "REDV_I2C_A0")
		)
		(pad "22" smd rect
			(at 3.999992 1.778)
			(size 0.3048 0.9652)
			(layers "B.Cu" "B.Mask" "B.Paste")
			(net "REDV_I2C_A1")
		)
		(pad "23" smd rect
			(at 3.50012 1.778)
			(size 0.3048 0.9652)
			(layers "B.Cu" "B.Mask" "B.Paste")
			(net "REDV_I2C_SEL2B")
		)
		(pad "24" smd rect
			(at 2.999994 1.778)
			(size 0.3048 0.9652)
			(layers "B.Cu" "B.Mask" "B.Paste")
			(net "REDV_I2C_SEL1B")
		)
		(pad "25" smd rect
			(at 2.500122 1.778)
			(size 0.3048 0.9652)
			(layers "B.Cu" "B.Mask" "B.Paste")
			(net "1.2V_REDV")
		)
		(pad "26" smd rect
			(at 1.999996 1.778)
			(size 0.3048 0.9652)
			(layers "B.Cu" "B.Mask" "B.Paste")
			(net "SAS_HDD_CONN_SER_RX8_N")
		)
		(pad "27" smd rect
			(at 1.500124 1.778)
			(size 0.3048 0.9652)
			(layers "B.Cu" "B.Mask" "B.Paste")
			(net "SAS_HDD_CONN_SER_RX8_P")
		)
		(pad "28" smd rect
			(at 0.999998 1.778)
			(size 0.3048 0.9652)
			(layers "B.Cu" "B.Mask" "B.Paste")
			(net "SAS_HDD_CONN_SER_TX8_N")
		)
		(pad "29" smd rect
			(at 0.500126 1.778)
			(size 0.3048 0.9652)
			(layers "B.Cu" "B.Mask" "B.Paste")
			(net "SAS_HDD_CONN_SER_TX8_P")
		)
		(pad "30" smd rect
			(at 0 1.778)
			(size 0.3048 0.9652)
			(layers "B.Cu" "B.Mask" "B.Paste")
			(net "1.2V_REDV")
		)
		(pad "31" smd rect
			(at -0.500126 1.778)
			(size 0.3048 0.9652)
			(layers "B.Cu" "B.Mask" "B.Paste")
			(net "1.2V_REDV")
		)
		(pad "32" smd rect
			(at -0.999998 1.778)
			(size 0.3048 0.9652)
			(layers "B.Cu" "B.Mask" "B.Paste")
			(net "SAS_HDD_CONN_SER_RX7_N")
		)
		(pad "33" smd rect
			(at -1.500124 1.778)
			(size 0.3048 0.9652)
			(layers "B.Cu" "B.Mask" "B.Paste")
			(net "SAS_HDD_CONN_SER_RX7_P")
		)
		(pad "34" smd rect
			(at -1.999996 1.778)
			(size 0.3048 0.9652)
			(layers "B.Cu" "B.Mask" "B.Paste")
			(net "SAS_HDD_CONN_SER_TX7_N")
		)
		(pad "35" smd rect
			(at -2.500122 1.778)
			(size 0.3048 0.9652)
			(layers "B.Cu" "B.Mask" "B.Paste")
			(net "SAS_HDD_CONN_SER_TX7_P")
		)
		(pad "36" smd rect
			(at -2.999994 1.778)
			(size 0.3048 0.9652)
			(layers "B.Cu" "B.Mask" "B.Paste")
			(net "1.2V_REDV")
		)
		(pad "37" smd rect
			(at -3.50012 1.778)
			(size 0.3048 0.9652)
			(layers "B.Cu" "B.Mask" "B.Paste")
			(net "REDV_PD#")
		)
		(pad "38" smd rect
			(at -3.999992 1.778)
			(size 0.3048 0.9652)
			(layers "B.Cu" "B.Mask" "B.Paste")
			(net "REDV_I2C_SDA")
		)
		(pad "39" smd rect
			(at -4.5212 0.750062)
			(size 0.9652 0.3048)
			(layers "B.Cu" "B.Mask" "B.Paste")
			(net "REDV_I2C_SCL")
		)
		(pad "40" smd rect
			(at -4.5212 0.249936)
			(size 0.9652 0.3048)
			(layers "B.Cu" "B.Mask" "B.Paste")
			(net "REDV_D2_A")
		)
		(pad "41" smd rect
			(at -4.5212 -0.249936)
			(size 0.9652 0.3048)
			(layers "B.Cu" "B.Mask" "B.Paste")
			(net "REDV_D1_A")
		)
		(pad "42" smd rect
			(at -4.5212 -0.750062)
			(size 0.9652 0.3048)
			(layers "B.Cu" "B.Mask" "B.Paste")
			(net "REDV_I2C_SEL2A")
		)
		(pad "43" smd rect
			(at 0 0)
			(size 7.6454 2.159)
			(layers "B.Cu" "B.Mask" "B.Paste")
			(net "GND")
		)
	)
	(footprint ""
		(layer "B.Cu")
		(at 19.373088 -191.136016 90)
		(property "Reference" "SC545"
			(at 0 0 90)
			(layer "B.SilkS")
			(hide yes)
			(effects
				(font
					(size 1.27 1.27)
				)
				(justify mirror)
			)
		)
		(property "Value" "SCD1U16V2KX-3GP"
			(at -1.1811 -2.7051 90)
			(unlocked yes)
			(layer "B.Fab")
			(hide yes)
			(effects
				(font
					(size 1.016 1.016)
					(thickness 0.1524)
				)
				(justify mirror)
			)
		)
		(property "Device Type" "C402H22"
			(at -1.1811 -4.2291 90)
			(unlocked yes)
			(layer "B.Fab")
			(hide yes)
			(effects
				(font
					(size 1.016 1.016)
					(thickness 0.1524)
				)
				(justify mirror)
			)
		)
		(duplicate_pad_numbers_are_jumpers no)
		(fp_rect
			(start 0.4318 0.9525)
			(end -0.4318 -0.9525)
			(stroke
				(width 0)
				(type default)
			)
			(fill no)
			(layer "B.CrtYd")
		)
		(fp_rect
			(start 0.4318 0.9525)
			(end -0.4318 -0.9525)
			(stroke
				(width 0)
				(type default)
			)
			(fill no)
			(layer "B.Fab")
		)
		(pad "1" smd custom
			(at 0 -0.4445 270)
			(size 0.1524 0.1524)
			(layers "B.Cu" "B.Mask" "B.Paste")
			(net "P3V3_STBY")
			(options
				(clearance outline)
				(anchor circle)
			)
			(primitives
				(gr_poly
					(pts
						(arc
							(start 0.3048 0.2032)
							(mid 0.275042 0.275042)
							(end 0.2032 0.3048)
						)
						(arc
							(start -0.2032 0.3048)
							(mid -0.275042 0.275042)
							(end -0.3048 0.2032)
						)
						(arc
							(start -0.3048 -0.2032)
							(mid -0.275042 -0.275042)
							(end -0.2032 -0.3048)
						)
						(arc
							(start 0.2032 -0.3048)
							(mid 0.275042 -0.275042)
							(end 0.3048 -0.2032)
						)
					)
					(width 0)
					(fill yes)
				)
			)
		)
		(pad "2" smd custom
			(at 0 0.4445 270)
			(size 0.1524 0.1524)
			(layers "B.Cu" "B.Mask" "B.Paste")
			(net "GND")
			(options
				(clearance outline)
				(anchor circle)
			)
			(primitives
				(gr_poly
					(pts
						(arc
							(start 0.3048 0.2032)
							(mid 0.275042 0.275042)
							(end 0.2032 0.3048)
						)
						(arc
							(start -0.2032 0.3048)
							(mid -0.275042 0.275042)
							(end -0.3048 0.2032)
						)
						(arc
							(start -0.3048 -0.2032)
							(mid -0.275042 -0.275042)
							(end -0.2032 -0.3048)
						)
						(arc
							(start 0.2032 -0.3048)
							(mid 0.275042 -0.275042)
							(end 0.3048 -0.2032)
						)
					)
					(width 0)
					(fill yes)
				)
			)
		)
	)
	(footprint ""
		(layer "B.Cu")
		(at 105.264966 -48.26 90)
		(property "Reference" "SC1059"
			(at 0 0 90)
			(layer "B.SilkS")
			(hide yes)
			(effects
				(font
					(size 1.27 1.27)
				)
				(justify mirror)
			)
		)
		(property "Value" "SCD1U16V2KX-3GP"
			(at -1.1811 -2.7051 90)
			(unlocked yes)
			(layer "B.Fab")
			(hide yes)
			(effects
				(font
					(size 1.016 1.016)
					(thickness 0.1524)
				)
				(justify mirror)
			)
		)
		(property "Device Type" "C402H22"
			(at -1.1811 -4.2291 90)
			(unlocked yes)
			(layer "B.Fab")
			(hide yes)
			(effects
				(font
					(size 1.016 1.016)
					(thickness 0.1524)
				)
				(justify mirror)
			)
		)
		(duplicate_pad_numbers_are_jumpers no)
		(fp_rect
			(start 0.4318 0.9525)
			(end -0.4318 -0.9525)
			(stroke
				(width 0)
				(type default)
			)
			(fill no)
			(layer "B.CrtYd")
		)
		(fp_rect
			(start 0.4318 0.9525)
			(end -0.4318 -0.9525)
			(stroke
				(width 0)
				(type default)
			)
			(fill no)
			(layer "B.Fab")
		)
		(pad "1" smd custom
			(at 0 -0.4445 270)
			(size 0.1524 0.1524)
			(layers "B.Cu" "B.Mask" "B.Paste")
			(net "P0V955_C")
			(options
				(clearance outline)
				(anchor circle)
			)
			(primitives
				(gr_poly
					(pts
						(arc
							(start 0.3048 0.2032)
							(mid 0.275042 0.275042)
							(end 0.2032 0.3048)
						)
						(arc
							(start -0.2032 0.3048)
							(mid -0.275042 0.275042)
							(end -0.3048 0.2032)
						)
						(arc
							(start -0.3048 -0.2032)
							(mid -0.275042 -0.275042)
							(end -0.2032 -0.3048)
						)
						(arc
							(start 0.2032 -0.3048)
							(mid 0.275042 -0.275042)
							(end 0.3048 -0.2032)
						)
					)
					(width 0)
					(fill yes)
				)
			)
		)
		(pad "2" smd custom
			(at 0 0.4445 270)
			(size 0.1524 0.1524)
			(layers "B.Cu" "B.Mask" "B.Paste")
			(net "GND")
			(options
				(clearance outline)
				(anchor circle)
			)
			(primitives
				(gr_poly
					(pts
						(arc
							(start 0.3048 0.2032)
							(mid 0.275042 0.275042)
							(end 0.2032 0.3048)
						)
						(arc
							(start -0.2032 0.3048)
							(mid -0.275042 0.275042)
							(end -0.3048 0.2032)
						)
						(arc
							(start -0.3048 -0.2032)
							(mid -0.275042 -0.275042)
							(end -0.2032 -0.3048)
						)
						(arc
							(start 0.2032 -0.3048)
							(mid 0.275042 -0.275042)
							(end 0.3048 -0.2032)
						)
					)
					(width 0)
					(fill yes)
				)
			)
		)
	)
)
